FILE_TYPE = CONNECTIVITY;
{Allegro Design Entry HDL 17.4-2019 S026 (4007227) 1/17/2022}
"PAGE_NUMBER" = 106;
0"NC";
1"GND\g";
2"GND\g";
3"P3V3\g";
4"M_J_CPU1_SB_DQ<31:0>";
5"M_J_CPU1_SA_DQS_DP<9:0>";
6"M_J_CPU1_SA_DQS_DN<9:0>";
7"M_J_CPU1_SB_DQS_DP<9:0>";
8"M_J_CPU1_SB_DQS_DN<9:0>";
9"M_J_CPU1_SA_DQ<31:0>";
10"M_J_CPU1_SA_CA<6:0>";
11"M_J_CPU1_SB_CB<7:0>";
12"M_J_CPU1_SA_CB<7:0>";
13"M_J_CPU1_SB_CA<6:0>";
14"PD_CHJ_CPU1_DIMM_SAA";
15"I3C_SPD_DDRGL_CPU1_SDA";
16"I3C_SPD_DDRJ_CPU1_SDA";
17"PWRGD_CHJ_CPU1_DIMM";
18"I3C_SPD_DDRGL_CPU1_SCL";
19"P3V3_AUX\g";
20"I3C_SPD_DDRJ_CPU1_SCL";
21"M_J_CPU1_CLK_DN<0>";
22"M_J_CPU1_SB_CS_N<1>";
23"M_J_CPU1_ALERT_N";
24"M_J_CPU1_RESET_N";
25"M_J_CPU1_SA_CB<4>";
26"M_J_CPU1_SA_DQ<5>";
27"M_J_CPU1_SA_DQ<6>";
28"PWRGD_CHGL_CPU1";
29"P12V_MEM_CPU1\g";
30"M_J_CPU1_SA_RSP<0>";
31"M_J_CPU1_SB_DQ<11>";
32"GND\g";
33"PD_CHJ_CPU1_DIMM_SAA";
34"M_J_CPU1_SA_DQ<31>";
35"M_J_CPU1_SA_CB<7>";
36"M_J_CPU1_SA_CB<1>";
37"M_J_CPU1_SB_CB<7>";
38"M_J_CPU1_SA_CA<0>";
39"M_J_CPU1_SB_CA<0>";
40"M_J_CPU1_SA_CA<1>";
41"M_J_CPU1_SB_CA<1>";
42"M_J_CPU1_SA_CA<2>";
43"M_J_CPU1_SB_CA<2>";
44"M_J_CPU1_SB_CA<3>";
45"M_J_CPU1_SA_CA<4>";
46"M_J_CPU1_SB_CA<4>";
47"M_J_CPU1_SB_CA<5>";
48"M_J_CPU1_SB_CA<6>";
49"M_J_CPU1_SA_CB<6>";
50"M_J_CPU1_SA_CB<5>";
51"M_J_CPU1_SA_CB<3>";
52"M_J_CPU1_SA_CB<2>";
53"M_J_CPU1_SA_CB<0>";
54"M_J_CPU1_SB_CB<6>";
55"M_J_CPU1_SB_CB<5>";
56"M_J_CPU1_SB_CB<4>";
57"M_J_CPU1_SB_CB<3>";
58"M_J_CPU1_SB_CB<2>";
59"M_J_CPU1_SB_CB<1>";
60"M_J_CPU1_SB_CB<0>";
61"M_J_CPU1_CLK_DP<0>";
62"M_J_CPU1_SB_CS_N<0>";
63"M_J_CPU1_SA_CS_N<1>";
64"M_J_CPU1_SA_DQ<30>";
65"M_J_CPU1_SA_DQ<28>";
66"M_J_CPU1_SA_DQ<27>";
67"M_J_CPU1_SA_DQ<26>";
68"M_J_CPU1_SA_DQ<25>";
69"M_J_CPU1_SA_DQ<20>";
70"M_J_CPU1_SA_DQ<19>";
71"M_J_CPU1_SA_DQ<18>";
72"M_J_CPU1_SA_DQ<17>";
73"M_J_CPU1_SA_DQ<16>";
74"M_J_CPU1_SA_DQ<14>";
75"M_J_CPU1_SA_DQ<13>";
76"M_J_CPU1_SA_DQ<12>";
77"M_J_CPU1_SA_DQ<11>";
78"M_J_CPU1_SA_DQ<10>";
79"M_J_CPU1_SA_DQ<9>";
80"M_J_CPU1_SA_DQ<8>";
81"M_J_CPU1_SA_DQ<7>";
82"M_J_CPU1_SA_DQ<4>";
83"M_J_CPU1_SA_DQ<3>";
84"M_J_CPU1_SA_DQ<2>";
85"M_J_CPU1_SA_DQ<1>";
86"M_J_CPU1_SA_DQ<0>";
87"M_J_CPU1_SB_DQ<31>";
88"M_J_CPU1_SB_DQ<30>";
89"M_J_CPU1_SB_DQ<29>";
90"M_J_CPU1_SB_DQ<28>";
91"M_J_CPU1_SB_DQ<27>";
92"M_J_CPU1_SB_DQ<26>";
93"M_J_CPU1_SB_DQ<25>";
94"M_J_CPU1_SB_DQ<24>";
95"M_J_CPU1_SB_DQ<23>";
96"M_J_CPU1_SB_DQ<22>";
97"M_J_CPU1_SB_DQ<21>";
98"M_J_CPU1_SB_DQ<19>";
99"M_J_CPU1_SB_DQ<17>";
100"M_J_CPU1_SB_DQ<16>";
101"M_J_CPU1_SB_DQ<15>";
102"M_J_CPU1_SB_DQ<14>";
103"M_J_CPU1_SB_DQ<13>";
104"M_J_CPU1_SB_DQ<12>";
105"M_J_CPU1_SB_DQ<10>";
106"M_J_CPU1_SB_DQ<9>";
107"M_J_CPU1_SB_DQ<8>";
108"M_J_CPU1_SB_DQ<7>";
109"M_J_CPU1_SB_DQ<6>";
110"M_J_CPU1_SB_DQ<5>";
111"M_J_CPU1_SB_DQ<4>";
112"M_J_CPU1_SB_DQ<3>";
113"M_J_CPU1_SB_DQ<2>";
114"M_J_CPU1_SB_DQ<1>";
115"M_J_CPU1_SB_DQ<0>";
116"M_J_CPU1_SB_RSP<0>";
117"M_J_CPU1_SA_PAR";
118"M_J_CPU1_SB_PAR";
119"M_J_CPU1_SA_DQ<29>";
120"M_J_CPU1_SA_DQ<21>";
121"M_J_CPU1_SA_DQ<22>";
122"M_J_CPU1_SA_CA<3>";
123"M_J_CPU1_SA_CA<5>";
124"M_J_CPU1_SA_CA<6>";
125"M_J_CPU1_SA_DQ<24>";
126"M_J_CPU1_SA_DQ<23>";
127"M_J_CPU1_SA_DQ<15>";
128"M_J_CPU1_SA_DQS_DN<7>";
129"M_J_CPU1_SA_DQS_DP<6>";
130"M_J_CPU1_SB_DQS_DP<8>";
131"M_J_CPU1_SB_DQS_DN<8>";
132"M_J_CPU1_SB_DQS_DP<7>";
133"M_J_CPU1_SA_DQS_DN<0>";
134"M_J_CPU1_SA_DQS_DP<0>";
135"M_J_CPU1_SB_DQS_DN<0>";
136"M_J_CPU1_SB_DQS_DP<0>";
137"M_J_CPU1_SA_DQS_DN<1>";
138"M_J_CPU1_SA_DQS_DP<1>";
139"M_J_CPU1_SB_DQS_DN<1>";
140"M_J_CPU1_SB_DQS_DP<1>";
141"M_J_CPU1_SA_DQS_DN<2>";
142"M_J_CPU1_SA_DQS_DP<2>";
143"M_J_CPU1_SB_DQS_DN<2>";
144"M_J_CPU1_SB_DQS_DP<2>";
145"M_J_CPU1_SA_DQS_DN<3>";
146"M_J_CPU1_SA_DQS_DP<3>";
147"M_J_CPU1_SB_DQS_DN<3>";
148"M_J_CPU1_SB_DQS_DP<3>";
149"M_J_CPU1_SA_DQS_DN<4>";
150"M_J_CPU1_SA_DQS_DP<4>";
151"M_J_CPU1_SB_DQS_DN<4>";
152"M_J_CPU1_SB_DQS_DP<4>";
153"M_J_CPU1_SA_DQS_DN<5>";
154"M_J_CPU1_SA_DQS_DP<5>";
155"M_J_CPU1_SB_DQS_DN<5>";
156"M_J_CPU1_SB_DQS_DP<5>";
157"M_J_CPU1_SA_DQS_DN<6>";
158"M_J_CPU1_SB_DQS_DN<6>";
159"M_J_CPU1_SB_DQS_DP<6>";
160"M_J_CPU1_SA_DQS_DP<7>";
161"M_J_CPU1_SB_DQS_DN<7>";
162"M_J_CPU1_SA_DQS_DN<8>";
163"M_J_CPU1_SA_DQS_DP<8>";
164"M_J_CPU1_SB_DQS_DN<9>";
165"M_J_CPU1_SB_DQS_DP<9>";
166"M_J_CPU1_SA_DQS_DN<9>";
167"M_J_CPU1_SA_DQS_DP<9>";
168"GND\g";
169"GND\g";
170"M_J_CPU1_SA_CS_N<0>";
171"M_J_CPU1_SB_DQ<20>";
172"M_J_CPU1_SB_DQ<18>";
%"TAP"
"1","(-5850,4125)","0","mstr_standard","I100";
;
CDS_LIB"mstr_standard"
BODY_TYPE"PLUMBING"
HDL_TAP"TRUE";
"B \NAC \NWC"9;
"S \NAC"
BN"7"81;
%"TAP"
"1","(-5850,4175)","0","mstr_standard","I101";
;
CDS_LIB"mstr_standard"
BODY_TYPE"PLUMBING"
HDL_TAP"TRUE";
"B \NAC \NWC"9;
"S \NAC"
BN"8"80;
%"TAP"
"1","(-5850,4225)","0","mstr_standard","I102";
;
CDS_LIB"mstr_standard"
BODY_TYPE"PLUMBING"
HDL_TAP"TRUE";
"B \NAC \NWC"9;
"S \NAC"
BN"9"79;
%"TAP"
"1","(-5850,4275)","0","mstr_standard","I103";
;
CDS_LIB"mstr_standard"
BODY_TYPE"PLUMBING"
HDL_TAP"TRUE";
"B \NAC \NWC"9;
"S \NAC"
BN"10"78;
%"TAP"
"1","(-5850,4375)","0","mstr_standard","I104";
;
CDS_LIB"mstr_standard"
BODY_TYPE"PLUMBING"
HDL_TAP"TRUE";
"B \NAC \NWC"9;
"S \NAC"
BN"12"76;
%"TAP"
"1","(-5850,4325)","0","mstr_standard","I105";
;
CDS_LIB"mstr_standard"
BODY_TYPE"PLUMBING"
HDL_TAP"TRUE";
"B \NAC \NWC"9;
"S \NAC"
BN"11"77;
%"TAP"
"1","(-5850,4425)","0","mstr_standard","I106";
;
CDS_LIB"mstr_standard"
BODY_TYPE"PLUMBING"
HDL_TAP"TRUE";
"B \NAC \NWC"9;
"S \NAC"
BN"13"75;
%"TAP"
"1","(-5850,4475)","0","mstr_standard","I107";
;
CDS_LIB"mstr_standard"
BODY_TYPE"PLUMBING"
HDL_TAP"TRUE";
"B \NAC \NWC"9;
"S \NAC"
BN"14"74;
%"TAP"
"1","(-5850,4525)","0","mstr_standard","I108";
;
CDS_LIB"mstr_standard"
BODY_TYPE"PLUMBING"
HDL_TAP"TRUE";
"B \NAC \NWC"9;
"S \NAC"
BN"15"127;
%"TAP"
"1","(-5850,4575)","0","mstr_standard","I109";
;
CDS_LIB"mstr_standard"
BODY_TYPE"PLUMBING"
HDL_TAP"TRUE";
"B \NAC \NWC"9;
"S \NAC"
BN"16"73;
%"TAP"
"1","(-5850,4625)","0","mstr_standard","I110";
;
CDS_LIB"mstr_standard"
BODY_TYPE"PLUMBING"
HDL_TAP"TRUE";
"B \NAC \NWC"9;
"S \NAC"
BN"17"72;
%"TAP"
"1","(-5850,4675)","0","mstr_standard","I111";
;
CDS_LIB"mstr_standard"
BODY_TYPE"PLUMBING"
HDL_TAP"TRUE";
"B \NAC \NWC"9;
"S \NAC"
BN"18"71;
%"TAP"
"1","(-5850,4725)","0","mstr_standard","I112";
;
CDS_LIB"mstr_standard"
BODY_TYPE"PLUMBING"
HDL_TAP"TRUE";
"B \NAC \NWC"9;
"S \NAC"
BN"19"70;
%"TAP"
"1","(-5850,4775)","0","mstr_standard","I113";
;
CDS_LIB"mstr_standard"
BODY_TYPE"PLUMBING"
HDL_TAP"TRUE";
"B \NAC \NWC"9;
"S \NAC"
BN"20"69;
%"TAP"
"1","(-5850,4825)","0","mstr_standard","I114";
;
CDS_LIB"mstr_standard"
BODY_TYPE"PLUMBING"
HDL_TAP"TRUE";
"B \NAC \NWC"9;
"S \NAC"
BN"21"120;
%"TAP"
"1","(-5850,4875)","0","mstr_standard","I115";
;
CDS_LIB"mstr_standard"
BODY_TYPE"PLUMBING"
HDL_TAP"TRUE";
"B \NAC \NWC"9;
"S \NAC"
BN"22"121;
%"TAP"
"1","(-5850,4925)","0","mstr_standard","I116";
;
CDS_LIB"mstr_standard"
BODY_TYPE"PLUMBING"
HDL_TAP"TRUE";
"B \NAC \NWC"9;
"S \NAC"
BN"23"126;
%"TAP"
"1","(-5850,4975)","0","mstr_standard","I117";
;
CDS_LIB"mstr_standard"
BODY_TYPE"PLUMBING"
HDL_TAP"TRUE";
"B \NAC \NWC"9;
"S \NAC"
BN"24"125;
%"TAP"
"1","(-5850,5025)","0","mstr_standard","I118";
;
CDS_LIB"mstr_standard"
BODY_TYPE"PLUMBING"
HDL_TAP"TRUE";
"B \NAC \NWC"9;
"S \NAC"
BN"25"68;
%"TAP"
"1","(-5850,5075)","0","mstr_standard","I119";
;
CDS_LIB"mstr_standard"
BODY_TYPE"PLUMBING"
HDL_TAP"TRUE";
"B \NAC \NWC"9;
"S \NAC"
BN"26"67;
%"TAP"
"1","(-5850,5125)","0","mstr_standard","I120";
;
CDS_LIB"mstr_standard"
BODY_TYPE"PLUMBING"
HDL_TAP"TRUE";
"B \NAC \NWC"9;
"S \NAC"
BN"27"66;
%"TAP"
"1","(-5850,5175)","0","mstr_standard","I121";
;
CDS_LIB"mstr_standard"
BODY_TYPE"PLUMBING"
HDL_TAP"TRUE";
"B \NAC \NWC"9;
"S \NAC"
BN"28"65;
%"TAP"
"1","(-5850,5275)","0","mstr_standard","I122";
;
CDS_LIB"mstr_standard"
BODY_TYPE"PLUMBING"
HDL_TAP"TRUE";
"B \NAC \NWC"9;
"S \NAC"
BN"30"64;
%"TAP"
"1","(-5850,5225)","0","mstr_standard","I123";
;
CDS_LIB"mstr_standard"
BODY_TYPE"PLUMBING"
HDL_TAP"TRUE";
"B \NAC \NWC"9;
"S \NAC"
BN"29"119;
%"TAP"
"1","(-5850,5325)","0","mstr_standard","I124";
;
CDS_LIB"mstr_standard"
BODY_TYPE"PLUMBING"
HDL_TAP"TRUE";
"B \NAC \NWC"9;
"S \NAC"
BN"31"34;
%"GND"
"1","(-6250,950)","0","mstr_symbols","I126";
;
VOLTAGE"0.0"
CDS_LIB"mstr_symbols"
BOM_COST"MEM"
SIZE"1B"
BODY_TYPE"PLUMBING"
HDL_POWER"GND";
"A\NAC"1;
%"Q_RES"
"2","(-6250,1175)","0","pure_quanta","I127";
;
LOCATION"R776"
$SEC"1"
CDS_SEC"1"
PACK_TYPE"0402LF"
VALUE"35.7K"
TOLERANCE"1%"
MATERIAL"CHIP"
WATTAGE"1/16W"
CDS_LIB"pure_quanta"
PART_NUMBER"CS33572FB01";
"A"
$PN"1"33;
"B"
$PN"2"1;
%"GND"
"1","(-2025,1800)","0","mstr_symbols","I128";
;
VOLTAGE"0.0"
SIZE"1B"
CDS_LIB"mstr_symbols"
BODY_TYPE"PLUMBING"
HDL_POWER"GND";
"A\NAC"169;
%"GND"
"1","(-225,1575)","0","mstr_symbols","I142";
;
VOLTAGE"0.0"
SIZE"1B"
CDS_LIB"mstr_symbols"
BODY_TYPE"PLUMBING"
HDL_POWER"GND";
"A\NAC"168;
%"SCONN288_DDR506112002KQ"
"3","(-1125,3575)","0","pure_quanta","I143";
;
LOCATION"J29"
$SEC"3"
CDS_SEC"3"
MATERIAL"IO"
VALUE"SCONN288_DDR506112002KQ"
PART_TYPE"SMLF"
CDS_LIB"pure_quanta"
NEEDS_NO_SIZE"TRUE"
CDS_LMAN_SYM_OUTLINE"-450,1800,450,-1750"
PART_NUMBER"DFHST8FS479";
"G3"
$PN"G3"168;
"G2"
$PN"G2"168;
"G1"
$PN"G1"168;
"VSS62"
$PN"141"168;
"VSS61"
$PN"139"168;
"VSS60"
$PN"136"168;
"VSS58"
$PN"132"168;
"VSS104"
$PN"240"169;
"VSS102"
$PN"235"169;
"VSS100"
$PN"230"169;
"VIN_BULK2"
$PN"146"29;
"VIN_BULK1"
$PN"145"29;
"VIN_BULK0"
$PN"1"29;
"VSS126"
$PN"288"169;
"VSS125"
$PN"286"169;
"VSS124"
$PN"284"169;
"VSS123"
$PN"281"169;
"VSS122"
$PN"279"169;
"VSS121"
$PN"277"169;
"VSS120"
$PN"275"169;
"VSS119"
$PN"273"169;
"VSS118"
$PN"270"169;
"VSS117"
$PN"268"169;
"VSS116"
$PN"266"169;
"VSS115"
$PN"264"169;
"VSS114"
$PN"262"169;
"VSS113"
$PN"259"169;
"VSS112"
$PN"257"169;
"VSS111"
$PN"255"169;
"VSS110"
$PN"253"169;
"VSS109"
$PN"251"169;
"VSS108"
$PN"248"169;
"VSS107"
$PN"246"169;
"VSS106"
$PN"244"169;
"VSS105"
$PN"242"169;
"VSS103"
$PN"237"169;
"VSS101"
$PN"233"169;
"VSS99"
$PN"228"169;
"VSS98"
$PN"226"169;
"VSS97"
$PN"224"169;
"VSS96"
$PN"222"169;
"VSS95"
$PN"219"169;
"VSS94"
$PN"216"169;
"VSS93"
$PN"214"169;
"VSS92"
$PN"212"169;
"VSS91"
$PN"210"169;
"VSS90"
$PN"208"169;
"VSS89"
$PN"206"169;
"VSS88"
$PN"204"169;
"VSS87"
$PN"202"169;
"VSS86"
$PN"199"169;
"VSS85"
$PN"197"169;
"VSS84"
$PN"195"169;
"VSS83"
$PN"193"169;
"VSS82"
$PN"191"169;
"VSS81"
$PN"188"169;
"VSS80"
$PN"186"169;
"VSS79"
$PN"184"169;
"VSS78"
$PN"182"169;
"VSS77"
$PN"180"169;
"VSS76"
$PN"177"169;
"VSS75"
$PN"175"169;
"VSS74"
$PN"173"169;
"VSS73"
$PN"171"169;
"VSS72"
$PN"169"169;
"VSS71"
$PN"166"169;
"VSS70"
$PN"164"169;
"VSS69"
$PN"162"169;
"VSS68"
$PN"160"169;
"VSS67"
$PN"158"169;
"VSS66"
$PN"155"169;
"VSS65"
$PN"153"169;
"VSS64"
$PN"151"169;
"VSS63"
$PN"143"168;
"VSS59"
$PN"134"168;
"VSS57"
$PN"130"168;
"VSS56"
$PN"128"168;
"VSS55"
$PN"125"168;
"VSS54"
$PN"123"168;
"VSS53"
$PN"121"168;
"VSS52"
$PN"119"168;
"VSS51"
$PN"117"168;
"VSS50"
$PN"114"168;
"VSS49"
$PN"112"168;
"VSS48"
$PN"110"168;
"VSS47"
$PN"108"168;
"VSS46"
$PN"106"168;
"VSS45"
$PN"103"168;
"VSS44"
$PN"101"168;
"VSS43"
$PN"99"168;
"VSS42"
$PN"97"168;
"VSS41"
$PN"95"168;
"VSS40"
$PN"92"168;
"VSS39"
$PN"90"168;
"VSS38"
$PN"88"168;
"VSS37"
$PN"85"168;
"VSS36"
$PN"83"168;
"VSS35"
$PN"81"168;
"VSS34"
$PN"79"168;
"VSS33"
$PN"77"168;
"VSS32"
$PN"75"168;
"VSS31"
$PN"73"168;
"VSS30"
$PN"71"168;
"VSS29"
$PN"69"168;
"VSS28"
$PN"67"168;
"VSS27"
$PN"65"168;
"VSS26"
$PN"63"168;
"VSS25"
$PN"61"168;
"VSS24"
$PN"59"168;
"VSS23"
$PN"57"168;
"VSS22"
$PN"54"168;
"VSS21"
$PN"52"168;
"VSS20"
$PN"50"168;
"VSS19"
$PN"48"168;
"VSS18"
$PN"46"168;
"VSS17"
$PN"43"168;
"VSS16"
$PN"41"168;
"VSS15"
$PN"39"168;
"VSS14"
$PN"37"168;
"VSS13"
$PN"35"168;
"VSS12"
$PN"32"168;
"VSS11"
$PN"30"168;
"VSS10"
$PN"28"168;
"VSS9"
$PN"26"168;
"VSS8"
$PN"24"168;
"VSS7"
$PN"21"168;
"VSS6"
$PN"19"168;
"VSS5"
$PN"17"168;
"VSS4"
$PN"15"168;
"VSS3"
$PN"13"168;
"VSS2"
$PN"10"168;
"VSS1"
$PN"8"168;
"VSS0"
$PN"6"168;
%"Q_CAP"
"1","(-8525,3150)","2","pure_quanta","I185";
;
LOCATION"C172"
$SEC"1"
CDS_SEC"1"
MATERIAL"X7R"
VALUE"0.1UF"
TOLERANCE"10%"
PACK_TYPE"0402"
VOLTAGE"25V"
BOM_COST"MEM"
CDS_LIB"pure_quanta"
ROOM""
PART_NUMBER"CH4104K1B00";
"B"
$PN"2"2;
"A"
$PN"1"19;
%"GND"
"1","(-8525,2925)","0","mstr_symbols","I186";
;
ROOM"MEM_EFGH_DECOUPLING_CAPS"
VOLTAGE"0"
CDS_LIB"mstr_symbols"
SIZE"1B"
BOM_COST"MEM"
BODY_TYPE"PLUMBING"
HDL_POWER"GND";
"A\NAC"2;
%"Q_RES"
"1","(-8375,2075)","2","pure_quanta","I188";
;
LOCATION"R312"
$SEC"1"
CDS_SEC"1"
VALUE"1K"
PACK_TYPE"0402LF"
MATERIAL"CHIP"
WATTAGE"1/16W"
CDS_LIB"pure_quanta"
BOM_COST"MEM"
TOLERANCE"1%"
ROOM""
PART_NUMBER"CS21002FB06";
"B"
$PN"2"28;
"A"
$PN"1"17;
%"VCC_CORE"
"1","(-8250,2400)","0","mstr_symbols","I189";
;
HDL_POWER"P3V3"
ROOM"PVCCINFAON_CPU0_CTRL"
VOLTAGE"3.3"
CDS_LIB"mstr_symbols";
"A"3;
%"Q_RES"
"2","(-8250,2225)","0","pure_quanta","I190";
;
LOCATION"R113"
$SEC"1"
CDS_SEC"1"
WATTAGE"1/16W"
PACK_TYPE"0402LF"
MATERIAL"EMPTY"
VALUE"1K"
TOLERANCE"1%"
CDS_LIB"pure_quanta"
BOM_COST"MEM"
ROOM""
PART_NUMBER"CS21002FB06";
"A"
$PN"1"3;
"B"
$PN"2"17;
%"TAP"
"1","(-3150,4600)","0","mstr_standard","I196";
;
CDS_LIB"mstr_standard"
BODY_TYPE"PLUMBING"
HDL_TAP"TRUE";
"B \NAC \NWC"6;
"S \NAC"
BN"9"166;
%"TAP"
"1","(-3350,4650)","0","mstr_standard","I197";
;
CDS_LIB"mstr_standard"
BODY_TYPE"PLUMBING"
HDL_TAP"TRUE";
"B \NAC \NWC"5;
"S \NAC"
BN"9"167;
%"TAP"
"1","(-3350,4550)","0","mstr_standard","I198";
;
CDS_LIB"mstr_standard"
BODY_TYPE"PLUMBING"
HDL_TAP"TRUE";
"B \NAC \NWC"5;
"S \NAC"
BN"8"163;
%"TAP"
"1","(-3150,4500)","0","mstr_standard","I199";
;
CDS_LIB"mstr_standard"
BODY_TYPE"PLUMBING"
HDL_TAP"TRUE";
"B \NAC \NWC"6;
"S \NAC"
BN"8"162;
%"TAP"
"1","(-3150,4300)","0","mstr_standard","I200";
;
CDS_LIB"mstr_standard"
BODY_TYPE"PLUMBING"
HDL_TAP"TRUE";
"B \NAC \NWC"6;
"S \NAC"
BN"6"157;
%"TAP"
"1","(-3150,4400)","0","mstr_standard","I201";
;
CDS_LIB"mstr_standard"
BODY_TYPE"PLUMBING"
HDL_TAP"TRUE";
"B \NAC \NWC"6;
"S \NAC"
BN"7"128;
%"TAP"
"1","(-3150,4200)","0","mstr_standard","I202";
;
CDS_LIB"mstr_standard"
BODY_TYPE"PLUMBING"
HDL_TAP"TRUE";
"B \NAC \NWC"6;
"S \NAC"
BN"5"153;
%"TAP"
"1","(-3150,4100)","0","mstr_standard","I203";
;
CDS_LIB"mstr_standard"
BODY_TYPE"PLUMBING"
HDL_TAP"TRUE";
"B \NAC \NWC"6;
"S \NAC"
BN"4"149;
%"TAP"
"1","(-3150,4000)","0","mstr_standard","I204";
;
CDS_LIB"mstr_standard"
BODY_TYPE"PLUMBING"
HDL_TAP"TRUE";
"B \NAC \NWC"6;
"S \NAC"
BN"3"145;
%"TAP"
"1","(-3150,3800)","0","mstr_standard","I205";
;
CDS_LIB"mstr_standard"
BODY_TYPE"PLUMBING"
HDL_TAP"TRUE";
"B \NAC \NWC"6;
"S \NAC"
BN"1"137;
%"TAP"
"1","(-3150,3900)","0","mstr_standard","I206";
;
CDS_LIB"mstr_standard"
BODY_TYPE"PLUMBING"
HDL_TAP"TRUE";
"B \NAC \NWC"6;
"S \NAC"
BN"2"141;
%"TAP"
"1","(-3150,3700)","0","mstr_standard","I207";
;
CDS_LIB"mstr_standard"
BODY_TYPE"PLUMBING"
HDL_TAP"TRUE";
"B \NAC \NWC"6;
"S \NAC"
BN"0"133;
%"TAP"
"1","(-3150,3550)","0","mstr_standard","I208";
;
CDS_LIB"mstr_standard"
BODY_TYPE"PLUMBING"
HDL_TAP"TRUE";
"B \NAC \NWC"8;
"S \NAC"
BN"9"164;
%"TAP"
"1","(-3350,4450)","0","mstr_standard","I209";
;
CDS_LIB"mstr_standard"
BODY_TYPE"PLUMBING"
HDL_TAP"TRUE";
"B \NAC \NWC"5;
"S \NAC"
BN"7"160;
%"TAP"
"1","(-3350,4350)","0","mstr_standard","I210";
;
CDS_LIB"mstr_standard"
BODY_TYPE"PLUMBING"
HDL_TAP"TRUE";
"B \NAC \NWC"5;
"S \NAC"
BN"6"129;
%"TAP"
"1","(-3350,4250)","0","mstr_standard","I211";
;
CDS_LIB"mstr_standard"
BODY_TYPE"PLUMBING"
HDL_TAP"TRUE";
"B \NAC \NWC"5;
"S \NAC"
BN"5"154;
%"TAP"
"1","(-3350,4050)","0","mstr_standard","I212";
;
CDS_LIB"mstr_standard"
BODY_TYPE"PLUMBING"
HDL_TAP"TRUE";
"B \NAC \NWC"5;
"S \NAC"
BN"3"146;
%"TAP"
"1","(-3350,4150)","0","mstr_standard","I213";
;
CDS_LIB"mstr_standard"
BODY_TYPE"PLUMBING"
HDL_TAP"TRUE";
"B \NAC \NWC"5;
"S \NAC"
BN"4"150;
%"TAP"
"1","(-3350,3950)","0","mstr_standard","I214";
;
CDS_LIB"mstr_standard"
BODY_TYPE"PLUMBING"
HDL_TAP"TRUE";
"B \NAC \NWC"5;
"S \NAC"
BN"2"142;
%"TAP"
"1","(-3350,3850)","0","mstr_standard","I215";
;
CDS_LIB"mstr_standard"
BODY_TYPE"PLUMBING"
HDL_TAP"TRUE";
"B \NAC \NWC"5;
"S \NAC"
BN"1"138;
%"TAP"
"1","(-3350,3600)","0","mstr_standard","I216";
;
CDS_LIB"mstr_standard"
BODY_TYPE"PLUMBING"
HDL_TAP"TRUE";
"B \NAC \NWC"7;
"S \NAC"
BN"9"165;
%"TAP"
"1","(-3350,3750)","0","mstr_standard","I217";
;
CDS_LIB"mstr_standard"
BODY_TYPE"PLUMBING"
HDL_TAP"TRUE";
"B \NAC \NWC"5;
"S \NAC"
BN"0"134;
%"TAP"
"1","(-3150,3450)","0","mstr_standard","I218";
;
CDS_LIB"mstr_standard"
BODY_TYPE"PLUMBING"
HDL_TAP"TRUE";
"B \NAC \NWC"8;
"S \NAC"
BN"8"131;
%"TAP"
"1","(-3150,3350)","0","mstr_standard","I219";
;
CDS_LIB"mstr_standard"
BODY_TYPE"PLUMBING"
HDL_TAP"TRUE";
"B \NAC \NWC"8;
"S \NAC"
BN"7"161;
%"SCONN288_DDR506112002KQ"
"1","(-6700,3575)","0","pure_quanta","I22";
;
LOCATION"J29"
$SEC"1"
CDS_SEC"1"
MATERIAL"IO"
VALUE"SCONN288_DDR506112002KQ"
PART_TYPE"SMLF"
CDS_LIB"pure_quanta"
NEEDS_NO_SIZE"TRUE"
CDS_LMAN_SYM_OUTLINE"-450,1900,450,-1850"
PART_NUMBER"DFHST8FS479";
"PWR_GOOD||FAIL_N"
$PN"147"17;
"DQ31_A"
$PN"194"34;
"CB7_A"
$PN"205"35;
"CB4_A"
$PN"58"25;
"CB1_A"
$PN"53"36;
"CB7_B"
$PN"236"37;
"ALERT_N \B"
$PN"62"23;
"CA0_A"
$PN"66"38;
"CA0_B"
$PN"76"39;
"CA1_A"
$PN"211"40;
"CA1_B"
$PN"221"41;
"CA2_A"
$PN"68"42;
"CA2_B"
$PN"78"43;
"CA3_A"
$PN"213"122;
"CA3_B"
$PN"223"44;
"CA4_A"
$PN"70"45;
"CA4_B"
$PN"80"46;
"CA5_A"
$PN"215"123;
"CA5_B"
$PN"225"47;
"CA6_A"
$PN"72"124;
"CA6_B"
$PN"82"48;
"CB6_A"
$PN"203"49;
"CB5_A"
$PN"60"50;
"CB3_A"
$PN"198"51;
"CB2_A"
$PN"196"52;
"CB0_A"
$PN"51"53;
"CB6_B"
$PN"234"54;
"CB5_B"
$PN"91"55;
"CB4_B"
$PN"89"56;
"CB3_B"
$PN"243"57;
"CB2_B"
$PN"241"58;
"CB1_B"
$PN"98"59;
"CB0_B"
$PN"96"60;
"CK_C \B"
$PN"218"21;
"CK_T"
$PN"217"61;
"CS0_A_N"
$PN"64"170;
"CS0_B_N"
$PN"84"62;
"CS1_A_N"
$PN"209"63;
"CS1_B_N"
$PN"229"22;
"DQ30_A"
$PN"192"64;
"DQ29_A"
$PN"49"119;
"DQ28_A"
$PN"47"65;
"DQ27_A"
$PN"187"66;
"DQ26_A"
$PN"185"67;
"DQ25_A"
$PN"42"68;
"DQ24_A"
$PN"40"125;
"DQ23_A"
$PN"183"126;
"DQ22_A"
$PN"181"121;
"DQ21_A"
$PN"38"120;
"DQ20_A"
$PN"36"69;
"DQ19_A"
$PN"176"70;
"DQ18_A"
$PN"174"71;
"DQ17_A"
$PN"31"72;
"DQ16_A"
$PN"29"73;
"DQ15_A"
$PN"172"127;
"DQ14_A"
$PN"170"74;
"DQ13_A"
$PN"27"75;
"DQ12_A"
$PN"25"76;
"DQ11_A"
$PN"165"77;
"DQ10_A"
$PN"163"78;
"DQ9_A"
$PN"20"79;
"DQ8_A"
$PN"18"80;
"DQ7_A"
$PN"161"81;
"DQ6_A"
$PN"159"27;
"DQ5_A"
$PN"16"26;
"DQ4_A"
$PN"14"82;
"DQ3_A"
$PN"154"83;
"DQ2_A"
$PN"152"84;
"DQ1_A"
$PN"9"85;
"DQ0_A"
$PN"7"86;
"DQ31_B"
$PN"287"87;
"DQ30_B"
$PN"285"88;
"DQ29_B"
$PN"142"89;
"DQ28_B"
$PN"140"90;
"DQ27_B"
$PN"280"91;
"DQ26_B"
$PN"278"92;
"DQ25_B"
$PN"135"93;
"DQ24_B"
$PN"133"94;
"DQ23_B"
$PN"276"95;
"DQ22_B"
$PN"274"96;
"DQ21_B"
$PN"131"97;
"DQ20_B"
$PN"129"171;
"DQ19_B"
$PN"269"98;
"DQ18_B"
$PN"267"172;
"DQ17_B"
$PN"124"99;
"DQ16_B"
$PN"122"100;
"DQ15_B"
$PN"265"101;
"DQ14_B"
$PN"263"102;
"DQ13_B"
$PN"120"103;
"DQ12_B"
$PN"118"104;
"DQ11_B"
$PN"258"31;
"DQ10_B"
$PN"256"105;
"DQ9_B"
$PN"113"106;
"DQ8_B"
$PN"111"107;
"DQ7_B"
$PN"254"108;
"DQ6_B"
$PN"252"109;
"DQ5_B"
$PN"109"110;
"DQ4_B"
$PN"107"111;
"DQ3_B"
$PN"247"112;
"DQ2_B"
$PN"245"113;
"DQ1_B"
$PN"102"114;
"DQ0_B"
$PN"100"115;
"HAS"
$PN"148"14;
"HSCL"
$PN"4"20;
"HSDA"
$PN"5"16;
"LBD||RSP_A_N"
$PN"86"30;
"LBS||RSP_B_N"
$PN"87"116;
"PAR_A"
$PN"74"117;
"PAR_B"
$PN"227"118;
"RESET_N \B"
$PN"207"24;
"RFU6"
$PN"232"0;
"RFU5"
$PN"231"0;
"RFU4"
$PN"220"0;
"RFU3"
$PN"150"0;
"RFU2"
$PN"149"0;
"RFU1"
$PN"144"0;
"RFU0"
$PN"2"0;
"VIN_MGMT"
$PN"3"19;
%"TAP"
"1","(-3150,3150)","0","mstr_standard","I220";
;
CDS_LIB"mstr_standard"
BODY_TYPE"PLUMBING"
HDL_TAP"TRUE";
"B \NAC \NWC"8;
"S \NAC"
BN"5"155;
%"TAP"
"1","(-3150,3250)","0","mstr_standard","I221";
;
CDS_LIB"mstr_standard"
BODY_TYPE"PLUMBING"
HDL_TAP"TRUE";
"B \NAC \NWC"8;
"S \NAC"
BN"6"158;
%"TAP"
"1","(-3150,3050)","0","mstr_standard","I222";
;
CDS_LIB"mstr_standard"
BODY_TYPE"PLUMBING"
HDL_TAP"TRUE";
"B \NAC \NWC"8;
"S \NAC"
BN"4"151;
%"TAP"
"1","(-3150,2950)","0","mstr_standard","I223";
;
CDS_LIB"mstr_standard"
BODY_TYPE"PLUMBING"
HDL_TAP"TRUE";
"B \NAC \NWC"8;
"S \NAC"
BN"3"147;
%"TAP"
"1","(-3150,2850)","0","mstr_standard","I224";
;
CDS_LIB"mstr_standard"
BODY_TYPE"PLUMBING"
HDL_TAP"TRUE";
"B \NAC \NWC"8;
"S \NAC"
BN"2"143;
%"TAP"
"1","(-3150,2750)","0","mstr_standard","I225";
;
CDS_LIB"mstr_standard"
BODY_TYPE"PLUMBING"
HDL_TAP"TRUE";
"B \NAC \NWC"8;
"S \NAC"
BN"1"139;
%"TAP"
"1","(-3150,2650)","0","mstr_standard","I226";
;
CDS_LIB"mstr_standard"
BODY_TYPE"PLUMBING"
HDL_TAP"TRUE";
"B \NAC \NWC"8;
"S \NAC"
BN"0"135;
%"TAP"
"1","(-3350,3500)","0","mstr_standard","I227";
;
CDS_LIB"mstr_standard"
BODY_TYPE"PLUMBING"
HDL_TAP"TRUE";
"B \NAC \NWC"7;
"S \NAC"
BN"8"130;
%"TAP"
"1","(-3350,3400)","0","mstr_standard","I228";
;
CDS_LIB"mstr_standard"
BODY_TYPE"PLUMBING"
HDL_TAP"TRUE";
"B \NAC \NWC"7;
"S \NAC"
BN"7"132;
%"TAP"
"1","(-3350,3300)","0","mstr_standard","I229";
;
CDS_LIB"mstr_standard"
BODY_TYPE"PLUMBING"
HDL_TAP"TRUE";
"B \NAC \NWC"7;
"S \NAC"
BN"6"159;
%"TAP"
"1","(-7550,3125)","2","mstr_standard","I23";
;
CDS_LIB"mstr_standard"
BODY_TYPE"PLUMBING"
HDL_TAP"TRUE";
"B \NAC \NWC"11;
"S \NAC"
BN"0"60;
%"TAP"
"1","(-3350,3200)","0","mstr_standard","I230";
;
CDS_LIB"mstr_standard"
BODY_TYPE"PLUMBING"
HDL_TAP"TRUE";
"B \NAC \NWC"7;
"S \NAC"
BN"5"156;
%"TAP"
"1","(-3350,3100)","0","mstr_standard","I231";
;
CDS_LIB"mstr_standard"
BODY_TYPE"PLUMBING"
HDL_TAP"TRUE";
"B \NAC \NWC"7;
"S \NAC"
BN"4"152;
%"TAP"
"1","(-3350,2900)","0","mstr_standard","I232";
;
CDS_LIB"mstr_standard"
BODY_TYPE"PLUMBING"
HDL_TAP"TRUE";
"B \NAC \NWC"7;
"S \NAC"
BN"2"144;
%"TAP"
"1","(-3350,3000)","0","mstr_standard","I233";
;
CDS_LIB"mstr_standard"
BODY_TYPE"PLUMBING"
HDL_TAP"TRUE";
"B \NAC \NWC"7;
"S \NAC"
BN"3"148;
%"TAP"
"1","(-3350,2800)","0","mstr_standard","I234";
;
CDS_LIB"mstr_standard"
BODY_TYPE"PLUMBING"
HDL_TAP"TRUE";
"B \NAC \NWC"7;
"S \NAC"
BN"1"140;
%"TAP"
"1","(-3350,2700)","0","mstr_standard","I235";
;
CDS_LIB"mstr_standard"
BODY_TYPE"PLUMBING"
HDL_TAP"TRUE";
"B \NAC \NWC"7;
"S \NAC"
BN"0"136;
%"SCONN288_DDR506112002KQ"
"2","(-4300,3650)","0","pure_quanta","I236";
;
LOCATION"J29"
$SEC"2"
CDS_SEC"2"
MATERIAL"IO"
PART_TYPE"SMLF"
VALUE"SCONN288_DDR506112002KQ"
CDS_LIB"pure_quanta"
NEEDS_NO_SIZE"TRUE"
CDS_LMAN_SYM_OUTLINE"-600,1150,600,-1150"
PART_NUMBER"DFHST8FS479";
"DQS7_A_C||TDQS7_A_C \B"
$PN"178"128;
"DQS6_A_T||TDQS6_A_T"
$PN"168"129;
"DQS8_B_T||TDQS8_B_T"
$PN"283"130;
"DQS8_B_C||TDQS8_B_C \B"
$PN"282"131;
"DQS7_B_T||TDQS7_B_T"
$PN"272"132;
"DQS0_A_C \B"
$PN"12"133;
"DQS0_A_T"
$PN"11"134;
"DQS0_B_C \B"
$PN"105"135;
"DQS0_B_T"
$PN"104"136;
"DQS1_A_C \B"
$PN"23"137;
"DQS1_A_T"
$PN"22"138;
"DQS1_B_C \B"
$PN"116"139;
"DQS1_B_T"
$PN"115"140;
"DQS2_A_C \B"
$PN"34"141;
"DQS2_A_T"
$PN"33"142;
"DQS2_B_C \B"
$PN"127"143;
"DQS2_B_T"
$PN"126"144;
"DQS3_A_C \B"
$PN"45"145;
"DQS3_A_T"
$PN"44"146;
"DQS3_B_C \B"
$PN"138"147;
"DQS3_B_T"
$PN"137"148;
"DQS4_A_C \B"
$PN"56"149;
"DQS4_A_T"
$PN"55"150;
"DQS4_B_C \B"
$PN"238"151;
"DQS4_B_T"
$PN"239"152;
"DQS5_A_C||TDQS5_A_C||DQS5_A_T||TDQS5_A_T \B"
$PN"156"153;
"DQS5_A_T||TDQS5_A_T"
$PN"157"154;
"DQS5_B_C||TDQS5_B_C \B"
$PN"249"155;
"DQS5_B_T||TDQS5_B_T"
$PN"250"156;
"DQS6_A_C||TDQS6_A_C||DQS6_A_T||TDQS6_A_T \B"
$PN"167"157;
"DQS6_B_C||TDQS6_B_C \B"
$PN"260"158;
"DQS6_B_T||TDQS6_B_T"
$PN"261"159;
"DQS7_A_T||TDQS7_A_T"
$PN"179"160;
"DQS7_B_C||TDQS7_B_C \B"
$PN"271"161;
"DQS8_A_C||TDQS8_A_C \B"
$PN"189"162;
"DQS8_A_T||TDQS8_A_T"
$PN"190"163;
"DQS9_A_C||TDQS9_A_C \B"
$PN"200"166;
"DQS9_A_T||TDQS9_A_T"
$PN"201"167;
"DQS9_B_C||TDQS9_B_C \B"
$PN"94"164;
"DQS9_B_T||TDQS9_B_T||DBI4_B_N"
$PN"93"165;
%"GND"
"1","(-2725,5425)","0","pure_quanta_power","I237";
;
ROOM"MEM_EFGH_DECOUPLING_CAPS"
SIZE"1B"
BOM_COST"MEM"
CDS_LIB"pure_quanta_power"
HDL_POWER"GND";
"A<SIZE-1..0>\NAC"32;
%"Q_CAP"
"1","(-2725,5775)","2","pure_quanta","I238";
;
LOCATION"C536"
$SEC"1"
CDS_SEC"1"
MATERIAL"X6S"
TOLERANCE"10%"
VALUE"10UF"
VOLTAGE"25V"
PACK_TYPE"C0805"
BOM_COST"MEM"
CDS_LIB"pure_quanta"
ROOM""
PART_NUMBER"CH6104KEA00";
"B"
$PN"2"32;
"A"
$PN"1"29;
%"Q_CAP"
"1","(-2150,5775)","2","pure_quanta","I239";
;
LOCATION"C537"
$SEC"1"
CDS_SEC"1"
MATERIAL"X6S"
TOLERANCE"10%"
VALUE"10UF"
VOLTAGE"25V"
PACK_TYPE"C0805"
BOM_COST"MEM"
CDS_LIB"pure_quanta"
ROOM""
PART_NUMBER"CH6104KEA00";
"B"
$PN"2"32;
"A"
$PN"1"29;
%"TAP"
"1","(-7550,3175)","2","mstr_standard","I24";
;
CDS_LIB"mstr_standard"
BODY_TYPE"PLUMBING"
HDL_TAP"TRUE";
"B \NAC \NWC"11;
"S \NAC"
BN"1"59;
%"UNIVERSAL_POWER"
"1","(-2725,6100)","0","pure_quanta_power","I240";
;
HDL_POWER"P12V_MEM_CPU1"
CDS_LIB"pure_quanta_power";
"A"29;
%"Q_RES"
"1","(-7600,2575)","0","pure_quanta","I242";
;
LOCATION"R1589"
$SEC"1"
CDS_SEC"1"
VALUE"49.9"
TOLERANCE"1%"
WATTAGE"1/16W"
PACK_TYPE"0402LF"
MATERIAL"CHIP"
CDS_LIB"pure_quanta"
PART_NUMBER"CS04992FB07";
"B"
$PN"2"20;
"A"
$PN"1"18;
%"Q_RES"
"1","(-8000,2775)","0","pure_quanta","I243";
;
LOCATION"R1709"
$SEC"1"
CDS_SEC"1"
PACK_TYPE"0402LF"
MATERIAL"CHIP"
VALUE"10"
CDS_LIB"pure_quanta"
WATTAGE"1/16W"
TOLERANCE"1%"
PART_NUMBER"CS01002FB07";
"B"
$PN"2"16;
"A"
$PN"1"15;
%"TAP"
"1","(-7550,3225)","2","mstr_standard","I25";
;
CDS_LIB"mstr_standard"
BODY_TYPE"PLUMBING"
HDL_TAP"TRUE";
"B \NAC \NWC"11;
"S \NAC"
BN"2"58;
%"TAP"
"1","(-7550,3325)","2","mstr_standard","I26";
;
CDS_LIB"mstr_standard"
BODY_TYPE"PLUMBING"
HDL_TAP"TRUE";
"B \NAC \NWC"11;
"S \NAC"
BN"4"56;
%"TAP"
"1","(-7550,3275)","2","mstr_standard","I27";
;
CDS_LIB"mstr_standard"
BODY_TYPE"PLUMBING"
HDL_TAP"TRUE";
"B \NAC \NWC"11;
"S \NAC"
BN"3"57;
%"TAP"
"1","(-7550,3375)","2","mstr_standard","I28";
;
CDS_LIB"mstr_standard"
BODY_TYPE"PLUMBING"
HDL_TAP"TRUE";
"B \NAC \NWC"11;
"S \NAC"
BN"5"55;
%"TAP"
"1","(-7550,3425)","2","mstr_standard","I29";
;
CDS_LIB"mstr_standard"
BODY_TYPE"PLUMBING"
HDL_TAP"TRUE";
"B \NAC \NWC"11;
"S \NAC"
BN"6"54;
%"TAP"
"1","(-7550,3475)","2","mstr_standard","I30";
;
CDS_LIB"mstr_standard"
BODY_TYPE"PLUMBING"
HDL_TAP"TRUE";
"B \NAC \NWC"11;
"S \NAC"
BN"7"37;
%"TAP"
"1","(-7550,3575)","2","mstr_standard","I31";
;
CDS_LIB"mstr_standard"
BODY_TYPE"PLUMBING"
HDL_TAP"TRUE";
"B \NAC \NWC"12;
"S \NAC"
BN"0"53;
%"TAP"
"1","(-7550,3625)","2","mstr_standard","I32";
;
CDS_LIB"mstr_standard"
BODY_TYPE"PLUMBING"
HDL_TAP"TRUE";
"B \NAC \NWC"12;
"S \NAC"
BN"1"36;
%"TAP"
"1","(-7550,3675)","2","mstr_standard","I33";
;
CDS_LIB"mstr_standard"
BODY_TYPE"PLUMBING"
HDL_TAP"TRUE";
"B \NAC \NWC"12;
"S \NAC"
BN"2"52;
%"TAP"
"1","(-7550,3725)","2","mstr_standard","I34";
;
CDS_LIB"mstr_standard"
BODY_TYPE"PLUMBING"
HDL_TAP"TRUE";
"B \NAC \NWC"12;
"S \NAC"
BN"3"51;
%"TAP"
"1","(-7550,3825)","2","mstr_standard","I35";
;
CDS_LIB"mstr_standard"
BODY_TYPE"PLUMBING"
HDL_TAP"TRUE";
"B \NAC \NWC"12;
"S \NAC"
BN"5"50;
%"TAP"
"1","(-7550,3775)","2","mstr_standard","I36";
;
CDS_LIB"mstr_standard"
BODY_TYPE"PLUMBING"
HDL_TAP"TRUE";
"B \NAC \NWC"12;
"S \NAC"
BN"4"25;
%"TAP"
"1","(-5850,2125)","0","mstr_standard","I37";
;
CDS_LIB"mstr_standard"
BODY_TYPE"PLUMBING"
HDL_TAP"TRUE";
"B \NAC \NWC"4;
"S \NAC"
BN"0"115;
%"TAP"
"1","(-5850,2175)","0","mstr_standard","I38";
;
CDS_LIB"mstr_standard"
BODY_TYPE"PLUMBING"
HDL_TAP"TRUE";
"B \NAC \NWC"4;
"S \NAC"
BN"1"114;
%"TAP"
"1","(-5850,2225)","0","mstr_standard","I39";
;
CDS_LIB"mstr_standard"
BODY_TYPE"PLUMBING"
HDL_TAP"TRUE";
"B \NAC \NWC"4;
"S \NAC"
BN"2"113;
%"TAP"
"1","(-5850,2275)","0","mstr_standard","I40";
;
CDS_LIB"mstr_standard"
BODY_TYPE"PLUMBING"
HDL_TAP"TRUE";
"B \NAC \NWC"4;
"S \NAC"
BN"3"112;
%"TAP"
"1","(-5850,2325)","0","mstr_standard","I41";
;
CDS_LIB"mstr_standard"
BODY_TYPE"PLUMBING"
HDL_TAP"TRUE";
"B \NAC \NWC"4;
"S \NAC"
BN"4"111;
%"TAP"
"1","(-5850,2425)","0","mstr_standard","I42";
;
CDS_LIB"mstr_standard"
BODY_TYPE"PLUMBING"
HDL_TAP"TRUE";
"B \NAC \NWC"4;
"S \NAC"
BN"6"109;
%"TAP"
"1","(-5850,2375)","0","mstr_standard","I43";
;
CDS_LIB"mstr_standard"
BODY_TYPE"PLUMBING"
HDL_TAP"TRUE";
"B \NAC \NWC"4;
"S \NAC"
BN"5"110;
%"TAP"
"1","(-5850,2525)","0","mstr_standard","I44";
;
CDS_LIB"mstr_standard"
BODY_TYPE"PLUMBING"
HDL_TAP"TRUE";
"B \NAC \NWC"4;
"S \NAC"
BN"8"107;
%"TAP"
"1","(-5850,2475)","0","mstr_standard","I45";
;
CDS_LIB"mstr_standard"
BODY_TYPE"PLUMBING"
HDL_TAP"TRUE";
"B \NAC \NWC"4;
"S \NAC"
BN"7"108;
%"TAP"
"1","(-5850,2575)","0","mstr_standard","I46";
;
CDS_LIB"mstr_standard"
BODY_TYPE"PLUMBING"
HDL_TAP"TRUE";
"B \NAC \NWC"4;
"S \NAC"
BN"9"106;
%"TAP"
"1","(-5850,2675)","0","mstr_standard","I47";
;
CDS_LIB"mstr_standard"
BODY_TYPE"PLUMBING"
HDL_TAP"TRUE";
"B \NAC \NWC"4;
"S \NAC"
BN"11"31;
%"TAP"
"1","(-5850,2625)","0","mstr_standard","I48";
;
CDS_LIB"mstr_standard"
BODY_TYPE"PLUMBING"
HDL_TAP"TRUE";
"B \NAC \NWC"4;
"S \NAC"
BN"10"105;
%"TAP"
"1","(-5850,2725)","0","mstr_standard","I49";
;
CDS_LIB"mstr_standard"
BODY_TYPE"PLUMBING"
HDL_TAP"TRUE";
"B \NAC \NWC"4;
"S \NAC"
BN"12"104;
%"TAP"
"1","(-5850,2775)","0","mstr_standard","I50";
;
CDS_LIB"mstr_standard"
BODY_TYPE"PLUMBING"
HDL_TAP"TRUE";
"B \NAC \NWC"4;
"S \NAC"
BN"13"103;
%"TAP"
"1","(-5850,2825)","0","mstr_standard","I51";
;
CDS_LIB"mstr_standard"
BODY_TYPE"PLUMBING"
HDL_TAP"TRUE";
"B \NAC \NWC"4;
"S \NAC"
BN"14"102;
%"TAP"
"1","(-5850,2925)","0","mstr_standard","I52";
;
CDS_LIB"mstr_standard"
BODY_TYPE"PLUMBING"
HDL_TAP"TRUE";
"B \NAC \NWC"4;
"S \NAC"
BN"16"100;
%"TAP"
"1","(-5850,2875)","0","mstr_standard","I53";
;
CDS_LIB"mstr_standard"
BODY_TYPE"PLUMBING"
HDL_TAP"TRUE";
"B \NAC \NWC"4;
"S \NAC"
BN"15"101;
%"TAP"
"1","(-5850,2975)","0","mstr_standard","I54";
;
CDS_LIB"mstr_standard"
BODY_TYPE"PLUMBING"
HDL_TAP"TRUE";
"B \NAC \NWC"4;
"S \NAC"
BN"17"99;
%"TAP"
"1","(-5850,3025)","0","mstr_standard","I55";
;
CDS_LIB"mstr_standard"
BODY_TYPE"PLUMBING"
HDL_TAP"TRUE";
"B \NAC \NWC"4;
"S \NAC"
BN"18"172;
%"TAP"
"1","(-5850,3075)","0","mstr_standard","I56";
;
CDS_LIB"mstr_standard"
BODY_TYPE"PLUMBING"
HDL_TAP"TRUE";
"B \NAC \NWC"4;
"S \NAC"
BN"19"98;
%"TAP"
"1","(-5850,3125)","0","mstr_standard","I57";
;
CDS_LIB"mstr_standard"
BODY_TYPE"PLUMBING"
HDL_TAP"TRUE";
"B \NAC \NWC"4;
"S \NAC"
BN"20"171;
%"TAP"
"1","(-5850,3175)","0","mstr_standard","I58";
;
CDS_LIB"mstr_standard"
BODY_TYPE"PLUMBING"
HDL_TAP"TRUE";
"B \NAC \NWC"4;
"S \NAC"
BN"21"97;
%"TAP"
"1","(-5850,3225)","0","mstr_standard","I59";
;
CDS_LIB"mstr_standard"
BODY_TYPE"PLUMBING"
HDL_TAP"TRUE";
"B \NAC \NWC"4;
"S \NAC"
BN"22"96;
%"TAP"
"1","(-5850,3325)","0","mstr_standard","I60";
;
CDS_LIB"mstr_standard"
BODY_TYPE"PLUMBING"
HDL_TAP"TRUE";
"B \NAC \NWC"4;
"S \NAC"
BN"24"94;
%"TAP"
"1","(-5850,3275)","0","mstr_standard","I61";
;
CDS_LIB"mstr_standard"
BODY_TYPE"PLUMBING"
HDL_TAP"TRUE";
"B \NAC \NWC"4;
"S \NAC"
BN"23"95;
%"TAP"
"1","(-5850,3375)","0","mstr_standard","I62";
;
CDS_LIB"mstr_standard"
BODY_TYPE"PLUMBING"
HDL_TAP"TRUE";
"B \NAC \NWC"4;
"S \NAC"
BN"25"93;
%"TAP"
"1","(-5850,3425)","0","mstr_standard","I63";
;
CDS_LIB"mstr_standard"
BODY_TYPE"PLUMBING"
HDL_TAP"TRUE";
"B \NAC \NWC"4;
"S \NAC"
BN"26"92;
%"TAP"
"1","(-5850,3475)","0","mstr_standard","I64";
;
CDS_LIB"mstr_standard"
BODY_TYPE"PLUMBING"
HDL_TAP"TRUE";
"B \NAC \NWC"4;
"S \NAC"
BN"27"91;
%"TAP"
"1","(-5850,3575)","0","mstr_standard","I65";
;
CDS_LIB"mstr_standard"
BODY_TYPE"PLUMBING"
HDL_TAP"TRUE";
"B \NAC \NWC"4;
"S \NAC"
BN"29"89;
%"TAP"
"1","(-5850,3525)","0","mstr_standard","I66";
;
CDS_LIB"mstr_standard"
BODY_TYPE"PLUMBING"
HDL_TAP"TRUE";
"B \NAC \NWC"4;
"S \NAC"
BN"28"90;
%"TAP"
"1","(-5850,3675)","0","mstr_standard","I67";
;
CDS_LIB"mstr_standard"
BODY_TYPE"PLUMBING"
HDL_TAP"TRUE";
"B \NAC \NWC"4;
"S \NAC"
BN"31"87;
%"TAP"
"1","(-5850,3625)","0","mstr_standard","I68";
;
CDS_LIB"mstr_standard"
BODY_TYPE"PLUMBING"
HDL_TAP"TRUE";
"B \NAC \NWC"4;
"S \NAC"
BN"30"88;
%"TAP"
"1","(-5850,3775)","0","mstr_standard","I69";
;
CDS_LIB"mstr_standard"
BODY_TYPE"PLUMBING"
HDL_TAP"TRUE";
"B \NAC \NWC"9;
"S \NAC"
BN"0"86;
%"VCC_CORE"
"1","(-8425,3350)","0","mstr_symbols","I7";
;
HDL_POWER"P3V3_AUX"
ROOM"PVCCINFAON_CPU1_CTRL"
VOLTAGE"3.3"
CDS_LIB"mstr_symbols";
"A"19;
%"TAP"
"1","(-5850,3825)","0","mstr_standard","I70";
;
CDS_LIB"mstr_standard"
BODY_TYPE"PLUMBING"
HDL_TAP"TRUE";
"B \NAC \NWC"9;
"S \NAC"
BN"1"85;
%"TAP"
"1","(-7550,3875)","2","mstr_standard","I79";
;
CDS_LIB"mstr_standard"
BODY_TYPE"PLUMBING"
HDL_TAP"TRUE";
"B \NAC \NWC"12;
"S \NAC"
BN"6"49;
%"TAP"
"1","(-7550,3925)","2","mstr_standard","I80";
;
CDS_LIB"mstr_standard"
BODY_TYPE"PLUMBING"
HDL_TAP"TRUE";
"B \NAC \NWC"12;
"S \NAC"
BN"7"35;
%"TAP"
"1","(-7550,4625)","2","mstr_standard","I81";
;
CDS_LIB"mstr_standard"
BODY_TYPE"PLUMBING"
HDL_TAP"TRUE";
"B \NAC \NWC"13;
"S \NAC"
BN"0"39;
%"TAP"
"1","(-7550,4725)","2","mstr_standard","I82";
;
CDS_LIB"mstr_standard"
BODY_TYPE"PLUMBING"
HDL_TAP"TRUE";
"B \NAC \NWC"13;
"S \NAC"
BN"2"43;
%"TAP"
"1","(-7550,4675)","2","mstr_standard","I83";
;
CDS_LIB"mstr_standard"
BODY_TYPE"PLUMBING"
HDL_TAP"TRUE";
"B \NAC \NWC"13;
"S \NAC"
BN"1"41;
%"TAP"
"1","(-7550,4825)","2","mstr_standard","I84";
;
CDS_LIB"mstr_standard"
BODY_TYPE"PLUMBING"
HDL_TAP"TRUE";
"B \NAC \NWC"13;
"S \NAC"
BN"4"46;
%"TAP"
"1","(-7550,4775)","2","mstr_standard","I85";
;
CDS_LIB"mstr_standard"
BODY_TYPE"PLUMBING"
HDL_TAP"TRUE";
"B \NAC \NWC"13;
"S \NAC"
BN"3"44;
%"TAP"
"1","(-7550,4875)","2","mstr_standard","I86";
;
CDS_LIB"mstr_standard"
BODY_TYPE"PLUMBING"
HDL_TAP"TRUE";
"B \NAC \NWC"13;
"S \NAC"
BN"5"47;
%"TAP"
"1","(-7550,4925)","2","mstr_standard","I87";
;
CDS_LIB"mstr_standard"
BODY_TYPE"PLUMBING"
HDL_TAP"TRUE";
"B \NAC \NWC"13;
"S \NAC"
BN"6"48;
%"TAP"
"1","(-7550,5025)","2","mstr_standard","I88";
;
CDS_LIB"mstr_standard"
BODY_TYPE"PLUMBING"
HDL_TAP"TRUE";
"B \NAC \NWC"10;
"S \NAC"
BN"0"38;
%"TAP"
"1","(-7550,5075)","2","mstr_standard","I89";
;
CDS_LIB"mstr_standard"
BODY_TYPE"PLUMBING"
HDL_TAP"TRUE";
"B \NAC \NWC"10;
"S \NAC"
BN"1"40;
%"TAP"
"1","(-7550,5125)","2","mstr_standard","I90";
;
CDS_LIB"mstr_standard"
BODY_TYPE"PLUMBING"
HDL_TAP"TRUE";
"B \NAC \NWC"10;
"S \NAC"
BN"2"42;
%"TAP"
"1","(-7550,5175)","2","mstr_standard","I91";
;
CDS_LIB"mstr_standard"
BODY_TYPE"PLUMBING"
HDL_TAP"TRUE";
"B \NAC \NWC"10;
"S \NAC"
BN"3"122;
%"TAP"
"1","(-7550,5225)","2","mstr_standard","I92";
;
CDS_LIB"mstr_standard"
BODY_TYPE"PLUMBING"
HDL_TAP"TRUE";
"B \NAC \NWC"10;
"S \NAC"
BN"4"45;
%"TAP"
"1","(-7550,5275)","2","mstr_standard","I93";
;
CDS_LIB"mstr_standard"
BODY_TYPE"PLUMBING"
HDL_TAP"TRUE";
"B \NAC \NWC"10;
"S \NAC"
BN"5"123;
%"TAP"
"1","(-7550,5325)","2","mstr_standard","I94";
;
CDS_LIB"mstr_standard"
BODY_TYPE"PLUMBING"
HDL_TAP"TRUE";
"B \NAC \NWC"10;
"S \NAC"
BN"6"124;
%"TAP"
"1","(-5850,3875)","0","mstr_standard","I95";
;
CDS_LIB"mstr_standard"
BODY_TYPE"PLUMBING"
HDL_TAP"TRUE";
"B \NAC \NWC"9;
"S \NAC"
BN"2"84;
%"TAP"
"1","(-5850,3925)","0","mstr_standard","I96";
;
CDS_LIB"mstr_standard"
BODY_TYPE"PLUMBING"
HDL_TAP"TRUE";
"B \NAC \NWC"9;
"S \NAC"
BN"3"83;
%"TAP"
"1","(-5850,3975)","0","mstr_standard","I97";
;
CDS_LIB"mstr_standard"
BODY_TYPE"PLUMBING"
HDL_TAP"TRUE";
"B \NAC \NWC"9;
"S \NAC"
BN"4"82;
%"TAP"
"1","(-5850,4025)","0","mstr_standard","I98";
;
CDS_LIB"mstr_standard"
BODY_TYPE"PLUMBING"
HDL_TAP"TRUE";
"B \NAC \NWC"9;
"S \NAC"
BN"5"26;
%"TAP"
"1","(-5850,4075)","0","mstr_standard","I99";
;
CDS_LIB"mstr_standard"
BODY_TYPE"PLUMBING"
HDL_TAP"TRUE";
"B \NAC \NWC"9;
"S \NAC"
BN"6"27;
END.
